# BASEBOARD_FAB2 (Tioga Pass) — schematic netlist excerpt (pin names and nets, part order shuffled) for the footprints in the layout excerpt that follows; sources: Cadence DE-HDL packaged netlist, KiCad conversion of Wiwynn_Tioga_Pass_MB.brd

C5G65  CAP_A  22.0UF 4V 20% X6S  pkg 0603V  page 242 : A = PVDDQ_DEF ; B = GND
R2T25  RES  1.00K 1% CHIP  pkg 0402  page 101 : A = PD_CKMNG_OE ; B = GND
C25W30  CAP  4.7UF 6.3V 10% X6S  pkg 0603  page 149 : A = P1V15_AUX_BMC ; B = GND

(kicad_pcb
	(version 20260206)
	(generator "pcbnew")
	(generator_version "10.0")
	(general
		(thickness 1.6)
		(legacy_teardrops no)
	)
	(paper "A4")
	(title_block
		(title "Wiwynn_Tioga_Pass_MB.brd")
		(comment 1 "Tioga Pass / footprints 4530-4532 of 4770")
	)
	(layers
		(0 "F.Cu" signal "TOP")
		(4 "In1.Cu" signal "L2GND")
		(6 "In2.Cu" signal "L3")
		(8 "In3.Cu" signal "L4GND")
		(10 "In4.Cu" signal "L5")
		(12 "In5.Cu" signal "L6GND")
		(14 "In6.Cu" signal "L7VCC")
		(16 "In7.Cu" signal "L8VCC")
		(18 "In8.Cu" signal "L9GND")
		(20 "In9.Cu" signal "L10")
		(22 "In10.Cu" signal "L11GND")
		(24 "In11.Cu" signal "L12")
		(26 "In12.Cu" signal "L13GND")
		(2 "B.Cu" signal "BOTTOM")
		(9 "F.Adhes" user "F.Adhesive")
		(11 "B.Adhes" user "B.Adhesive")
		(13 "F.Paste" user "Package Geometry/Pastemask Top")
		(15 "B.Paste" user "Package Geometry/Pastemask Bottom")
		(5 "F.SilkS" user "Ref Des/Silkscreen Top")
		(7 "B.SilkS" user "Ref Des/Silkscreen Bottom")
		(1 "F.Mask" user "Board Geometry/Soldermask Top")
		(3 "B.Mask" user "Board Geometry/Soldermask Bottom")
		(17 "Dwgs.User" user "User.Drawings")
		(19 "Cmts.User" user "User.Comments")
		(21 "Eco1.User" user "User.Eco1")
		(23 "Eco2.User" user "User.Eco2")
		(25 "Edge.Cuts" user "Board Geometry/Outline")
		(27 "Margin" user)
		(31 "F.CrtYd" user "Package Geometry/Place Bound Top")
		(29 "B.CrtYd" user "Package Geometry/Place Bound Bottom")
		(35 "F.Fab" user "Ref Des/Assembly Top")
		(33 "B.Fab" user "Ref Des/Assembly Bottom")
	)
	(footprint ""
		(layer "B.Cu")
		(at 248.8565 -140.208 -90)
		(property "Reference" "C5G65"
			(at -1.14681 0.76708 0)
			(unlocked yes)
			(layer "B.SilkS")
			(effects
				(font
					(size 0.7874 0.5842)
					(thickness 0.1524)
				)
				(justify mirror)
			)
		)
		(property "Value" ""
			(at 0 0 90)
			(layer "B.Fab")
			(effects
				(font
					(size 1.27 1.27)
				)
				(justify mirror)
			)
		)
		(duplicate_pad_numbers_are_jumpers no)
		(fp_rect
			(start 0.4953 1.6002)
			(end -0.4953 -0.2032)
			(stroke
				(width 0)
				(type default)
			)
			(fill no)
			(layer "B.CrtYd")
		)
		(fp_line
			(start -0.4953 1.6002)
			(end 0.4953 1.6002)
			(stroke
				(width 0.1)
				(type default)
			)
			(layer "B.Fab")
		)
		(fp_line
			(start 0.4953 1.6002)
			(end 0.4953 -0.2032)
			(stroke
				(width 0.1)
				(type default)
			)
			(layer "B.Fab")
		)
		(fp_line
			(start -0.4953 -0.2032)
			(end -0.4953 1.6002)
			(stroke
				(width 0.1)
				(type default)
			)
			(layer "B.Fab")
		)
		(fp_line
			(start 0.4953 -0.2032)
			(end -0.4953 -0.2032)
			(stroke
				(width 0.1)
				(type default)
			)
			(layer "B.Fab")
		)
		(pad "1" smd rect
			(at 0 0 90)
			(size 0.762 0.889)
			(layers "B.Cu" "B.Mask" "B.Paste")
			(net "PVDDQ_DEF")
		)
		(pad "2" smd rect
			(at 0 1.397 90)
			(size 0.762 0.889)
			(layers "B.Cu" "B.Mask" "B.Paste")
			(net "GND")
		)
		(zone
			(layer "B.Cu")
			(hatch none 0.5)
			(connect_pads
				(clearance 0)
			)
			(min_thickness 0.25)
			(keepout
				(tracks not_allowed)
				(vias allowed)
				(pads allowed)
				(copperpour not_allowed)
				(footprints allowed)
			)
			(placement
				(enabled no)
				(sheetname "")
			)
			(fill
				(thermal_gap 0.5)
				(thermal_bridge_width 0.5)
				(island_removal_mode 0)
			)
			(polygon
				(pts
					(xy 247.904 -139.827) (xy 248.412 -139.827) (xy 248.412 -140.589) (xy 247.904 -140.589)
				)
			)
		)
	)
	(footprint ""
		(layer "B.Cu")
		(at 477.84766 -27.70632 180)
		(property "Reference" "R2T25"
			(at 0 0 0)
			(layer "B.SilkS")
			(hide yes)
			(effects
				(font
					(size 1.27 1.27)
				)
				(justify mirror)
			)
		)
		(property "Value" ""
			(at 0 0 0)
			(layer "B.Fab")
			(effects
				(font
					(size 1.27 1.27)
				)
				(justify mirror)
			)
		)
		(duplicate_pad_numbers_are_jumpers no)
		(fp_poly
			(pts
				(xy 0.2794 -0.1016) (xy -0.2794 -0.1016) (xy -0.2794 0.9906) (xy 0.2794 0.9906)
			)
			(stroke
				(width 0)
				(type default)
			)
			(fill no)
			(layer "B.CrtYd")
		)
		(fp_line
			(start 0.2794 0.9906)
			(end -0.2794 0.9906)
			(stroke
				(width 0.1)
				(type default)
			)
			(layer "B.Fab")
		)
		(fp_line
			(start 0.2794 -0.1016)
			(end 0.2794 0.9906)
			(stroke
				(width 0.1)
				(type default)
			)
			(layer "B.Fab")
		)
		(fp_line
			(start -0.2794 0.9906)
			(end -0.2794 -0.1016)
			(stroke
				(width 0.1)
				(type default)
			)
			(layer "B.Fab")
		)
		(fp_line
			(start -0.2794 -0.1016)
			(end 0.2794 -0.1016)
			(stroke
				(width 0.1)
				(type default)
			)
			(layer "B.Fab")
		)
		(pad "1" smd rect
			(at 0 0)
			(size 0.508 0.508)
			(layers "B.Cu" "B.Mask" "B.Paste")
			(net "PD_CKMNG_OE")
		)
		(pad "2" smd rect
			(at 0 0.889)
			(size 0.508 0.508)
			(layers "B.Cu" "B.Mask" "B.Paste")
			(net "GND")
		)
		(zone
			(layer "B.Cu")
			(hatch none 0.5)
			(connect_pads
				(clearance 0)
			)
			(min_thickness 0.25)
			(keepout
				(tracks not_allowed)
				(vias allowed)
				(pads allowed)
				(copperpour not_allowed)
				(footprints allowed)
			)
			(placement
				(enabled no)
				(sheetname "")
			)
			(fill
				(thermal_gap 0.5)
				(thermal_bridge_width 0.5)
				(island_removal_mode 0)
			)
			(polygon
				(pts
					(xy 477.59366 -28.34132) (xy 478.10166 -28.34132) (xy 478.10166 -27.96032) (xy 477.59366 -27.96032)
				)
			)
		)
		(zone
			(layer "B.Cu")
			(hatch none 0.5)
			(connect_pads
				(clearance 0)
			)
			(min_thickness 0.25)
			(keepout
				(tracks allowed)
				(vias not_allowed)
				(pads allowed)
				(copperpour not_allowed)
				(footprints allowed)
			)
			(placement
				(enabled no)
				(sheetname "")
			)
			(fill
				(thermal_gap 0.5)
				(thermal_bridge_width 0.5)
				(island_removal_mode 0)
			)
			(polygon
				(pts
					(xy 477.59366 -27.96032) (xy 478.10166 -27.96032) (xy 478.10166 -28.34132) (xy 477.59366 -28.34132)
				)
			)
		)
	)
	(footprint ""
		(layer "B.Cu")
		(at 414.743646 -35.658552)
		(property "Reference" "C25W30"
			(at -0.97536 0.76708 90)
			(unlocked yes)
			(layer "B.SilkS")
			(effects
				(font
					(size 0.4064 0.254)
					(thickness 0.1524)
				)
				(justify mirror)
			)
		)
		(property "Value" ""
			(at 0 0 0)
			(layer "B.Fab")
			(effects
				(font
					(size 1.27 1.27)
				)
				(justify mirror)
			)
		)
		(duplicate_pad_numbers_are_jumpers no)
		(fp_poly
			(pts
				(xy 0.4953 -0.2032) (xy -0.4953 -0.2032) (xy -0.4953 1.6002) (xy 0.4953 1.6002)
			)
			(stroke
				(width 0)
				(type default)
			)
			(fill no)
			(layer "B.CrtYd")
		)
		(fp_line
			(start -0.4953 -0.2032)
			(end -0.4953 1.6002)
			(stroke
				(width 0.1)
				(type default)
			)
			(layer "B.Fab")
		)
		(fp_line
			(start -0.4953 1.6002)
			(end 0.4953 1.6002)
			(stroke
				(width 0.1)
				(type default)
			)
			(layer "B.Fab")
		)
		(fp_line
			(start 0.4953 -0.2032)
			(end -0.4953 -0.2032)
			(stroke
				(width 0.1)
				(type default)
			)
			(layer "B.Fab")
		)
		(fp_line
			(start 0.4953 1.6002)
			(end 0.4953 -0.2032)
			(stroke
				(width 0.1)
				(type default)
			)
			(layer "B.Fab")
		)
		(pad "1" smd rect
			(at 0 0 180)
			(size 0.762 0.889)
			(layers "B.Cu" "B.Mask" "B.Paste")
			(net "P1V15_AUX_BMC")
		)
		(pad "2" smd rect
			(at 0 1.397 180)
			(size 0.762 0.889)
			(layers "B.Cu" "B.Mask" "B.Paste")
			(net "GND")
		)
		(zone
			(layer "B.Cu")
			(hatch none 0.5)
			(connect_pads
				(clearance 0)
			)
			(min_thickness 0.25)
			(keepout
				(tracks not_allowed)
				(vias allowed)
				(pads allowed)
				(copperpour not_allowed)
				(footprints allowed)
			)
			(placement
				(enabled no)
				(sheetname "")
			)
			(fill
				(thermal_gap 0.5)
				(thermal_bridge_width 0.5)
				(island_removal_mode 0)
			)
			(polygon
				(pts
					(xy 415.124646 -35.214052) (xy 414.362646 -35.214052) (xy 414.362646 -34.706052) (xy 415.124646 -34.706052)
				)
			)
		)
	)
)
